# T6G (Grand Teton) — schematic netlist excerpt (pin names and nets, part order shuffled) for the footprints in the layout excerpt that follows; sources: Cadence DE-HDL packaged netlist, KiCad conversion of 04192023_DAF0TMB3IC0_F0TG_MB_C_brd_V02_OCP.brd

Q3  MOSFET_NCH_DUAL  PJT138K IC  pkg SOT363XD  page 188
  S1  = GND
  G1  = SW_P3V3_EN_R
  D2  = SW_P3V3_EN_ISO
  S2  = GND
  G2  = SW_P3V3_EN_N
  D1  = SW_P3V3_EN_N

PC153  Q_CAP  0.022UF 25V 10% X7R  pkg 0402  page 226 : A = PVDD18_S5_P1_REF ; B = GND

(kicad_pcb
	(version 20260206)
	(generator "pcbnew")
	(generator_version "10.0")
	(general
		(thickness 1.6)
		(legacy_teardrops no)
	)
	(paper "A4")
	(title_block
		(title "04192023_DAF0TMB3IC0_F0TG_MB_C_brd_V02_OCP.brd")
		(comment 1 "Grand Teton / footprints 1894-1895 of 8354")
	)
	(layers
		(0 "F.Cu" signal "TOP")
		(4 "In1.Cu" signal "GND")
		(6 "In2.Cu" signal "IN1")
		(8 "In3.Cu" signal "GND1")
		(10 "In4.Cu" signal "IN2")
		(12 "In5.Cu" signal "GND2")
		(14 "In6.Cu" signal "IN3")
		(16 "In7.Cu" signal "GND3")
		(18 "In8.Cu" signal "VCC")
		(20 "In9.Cu" signal "VCC1")
		(22 "In10.Cu" signal "GND4")
		(24 "In11.Cu" signal "IN4")
		(26 "In12.Cu" signal "GND5")
		(28 "In13.Cu" signal "IN5")
		(30 "In14.Cu" signal "GND6")
		(32 "In15.Cu" signal "IN6")
		(34 "In16.Cu" signal "GND7")
		(2 "B.Cu" signal "BOTTOM")
		(9 "F.Adhes" user "F.Adhesive")
		(11 "B.Adhes" user "B.Adhesive")
		(13 "F.Paste" user "Package Geometry/Pastemask Top")
		(15 "B.Paste" user "Package Geometry/Pastemask Bottom")
		(5 "F.SilkS" user "Ref Des/Silkscreen Top")
		(7 "B.SilkS" user "Ref Des/Silkscreen Bottom")
		(1 "F.Mask" user "Board Geometry/Soldermask Top")
		(3 "B.Mask" user "Board Geometry/Soldermask Bottom")
		(17 "Dwgs.User" user "User.Drawings")
		(19 "Cmts.User" user "User.Comments")
		(21 "Eco1.User" user "User.Eco1")
		(23 "Eco2.User" user "User.Eco2")
		(25 "Edge.Cuts" user "Board Geometry/Outline")
		(27 "Margin" user)
		(31 "F.CrtYd" user "Package Geometry/Place Bound Top")
		(29 "B.CrtYd" user "Package Geometry/Place Bound Bottom")
		(35 "F.Fab" user "Ref Des/Assembly Top")
		(33 "B.Fab" user "Ref Des/Assembly Bottom")
	)
	(footprint ""
		(layer "F.Cu")
		(at 208.28 -133.223 90)
		(property "Reference" "Q3"
			(at -0.741934 -3.189224 90)
			(unlocked yes)
			(layer "F.SilkS")
			(effects
				(font
					(size 0.7874 0.5842)
					(thickness 0.1524)
				)
				(justify left)
			)
		)
		(property "Value" ""
			(at 0 0 90)
			(layer "F.Fab")
			(effects
				(font
					(size 1.27 1.27)
				)
			)
		)
		(duplicate_pad_numbers_are_jumpers no)
		(fp_line
			(start 1.332738 -1.100074)
			(end 1.332738 1.100074)
			(stroke
				(width 0.1524)
				(type default)
			)
			(layer "F.SilkS")
		)
		(fp_line
			(start 0.4826 -1.100074)
			(end 1.332738 -1.100074)
			(stroke
				(width 0.1524)
				(type default)
			)
			(layer "F.SilkS")
		)
		(fp_line
			(start -0.4826 -1.100074)
			(end 0 -0.541274)
			(stroke
				(width 0.1524)
				(type default)
			)
			(layer "F.SilkS")
		)
		(fp_line
			(start -1.332738 -1.100074)
			(end -0.4826 -1.100074)
			(stroke
				(width 0.1524)
				(type default)
			)
			(layer "F.SilkS")
		)
		(fp_line
			(start 0 -0.541274)
			(end 0.4826 -1.100074)
			(stroke
				(width 0.1524)
				(type default)
			)
			(layer "F.SilkS")
		)
		(fp_line
			(start 1.332738 1.100074)
			(end -1.332738 1.100074)
			(stroke
				(width 0.1524)
				(type default)
			)
			(layer "F.SilkS")
		)
		(fp_line
			(start -1.332738 1.100074)
			(end -1.332738 -1.100074)
			(stroke
				(width 0.1524)
				(type default)
			)
			(layer "F.SilkS")
		)
		(fp_poly
			(pts
				(xy -2.699512 -0.335534) (xy -2.699512 -1.03759) (xy -1.997456 -0.686562)
			)
			(stroke
				(width 0)
				(type default)
			)
			(fill yes)
			(layer "F.SilkS")
		)
		(fp_line
			(start 0.674878 -1.100074)
			(end 0.674878 1.100074)
			(stroke
				(width 0.1)
				(type default)
			)
			(layer "F.Fab")
		)
		(fp_line
			(start -0.674878 -1.100074)
			(end 0.674878 -1.100074)
			(stroke
				(width 0.1)
				(type default)
			)
			(layer "F.Fab")
		)
		(fp_line
			(start 0.674878 1.100074)
			(end -0.674878 1.100074)
			(stroke
				(width 0.1)
				(type default)
			)
			(layer "F.Fab")
		)
		(fp_line
			(start -0.674878 1.100074)
			(end -0.674878 -1.100074)
			(stroke
				(width 0.1)
				(type default)
			)
			(layer "F.Fab")
		)
		(fp_poly
			(pts
				(xy -2.2352 -0.298958) (xy -2.2352 -1.001014) (xy -1.533144 -0.649986)
			)
			(stroke
				(width 0)
				(type default)
			)
			(fill yes)
			(layer "F.Fab")
		)
		(pad "1" smd rect
			(at -0.94996 -0.649986 180)
			(size 0.4318 0.508)
			(layers "F.Cu" "F.Mask" "F.Paste")
			(net "GND")
		)
		(pad "2" smd rect
			(at -0.94996 0 180)
			(size 0.4318 0.508)
			(layers "F.Cu" "F.Mask" "F.Paste")
			(net "SW_P3V3_EN_R")
		)
		(pad "3" smd rect
			(at -0.94996 0.649986 180)
			(size 0.4318 0.508)
			(layers "F.Cu" "F.Mask" "F.Paste")
			(net "SW_P3V3_EN_ISO")
		)
		(pad "4" smd rect
			(at 0.94996 0.649986 180)
			(size 0.4318 0.508)
			(layers "F.Cu" "F.Mask" "F.Paste")
			(net "GND")
		)
		(pad "5" smd rect
			(at 0.94996 0 180)
			(size 0.4318 0.508)
			(layers "F.Cu" "F.Mask" "F.Paste")
			(net "SW_P3V3_EN_N")
		)
		(pad "6" smd rect
			(at 0.94996 -0.649986 180)
			(size 0.4318 0.508)
			(layers "F.Cu" "F.Mask" "F.Paste")
			(net "SW_P3V3_EN_N")
		)
	)
	(footprint ""
		(layer "F.Cu")
		(at 70.307454 -147.339812 -90)
		(property "Reference" "PC153"
			(at 0 0 270)
			(layer "F.SilkS")
			(hide yes)
			(effects
				(font
					(size 1.27 1.27)
				)
			)
		)
		(property "Value" ""
			(at 0 0 270)
			(layer "F.Fab")
			(effects
				(font
					(size 1.27 1.27)
				)
			)
		)
		(duplicate_pad_numbers_are_jumpers no)
		(fp_line
			(start -0.7874 0.4064)
			(end -0.7874 -0.4064)
			(stroke
				(width 0.1524)
				(type default)
			)
			(layer "F.SilkS")
		)
		(fp_line
			(start 0.7874 0.4064)
			(end -0.7874 0.4064)
			(stroke
				(width 0.1524)
				(type default)
			)
			(layer "F.SilkS")
		)
		(fp_line
			(start -0.7874 -0.4064)
			(end 0.7874 -0.4064)
			(stroke
				(width 0.1524)
				(type default)
			)
			(layer "F.SilkS")
		)
		(fp_line
			(start 0.7874 -0.4064)
			(end 0.7874 0.4064)
			(stroke
				(width 0.1524)
				(type default)
			)
			(layer "F.SilkS")
		)
		(fp_line
			(start -0.67945 0.3048)
			(end -0.67945 -0.305054)
			(stroke
				(width 0.1)
				(type default)
			)
			(layer "F.Fab")
		)
		(fp_line
			(start -0.12065 0.3048)
			(end -0.67945 0.3048)
			(stroke
				(width 0.1)
				(type default)
			)
			(layer "F.Fab")
		)
		(fp_line
			(start 0.120396 0.3048)
			(end 0.120396 0.2794)
			(stroke
				(width 0.1)
				(type default)
			)
			(layer "F.Fab")
		)
		(fp_line
			(start 0.67945 0.3048)
			(end 0.120396 0.3048)
			(stroke
				(width 0.1)
				(type default)
			)
			(layer "F.Fab")
		)
		(fp_line
			(start -0.12065 0.2794)
			(end -0.12065 0.3048)
			(stroke
				(width 0.1)
				(type default)
			)
			(layer "F.Fab")
		)
		(fp_line
			(start 0.120396 0.2794)
			(end -0.12065 0.2794)
			(stroke
				(width 0.1)
				(type default)
			)
			(layer "F.Fab")
		)
		(fp_line
			(start -0.12065 -0.2794)
			(end 0.12065 -0.2794)
			(stroke
				(width 0.1)
				(type default)
			)
			(layer "F.Fab")
		)
		(fp_line
			(start 0.12065 -0.2794)
			(end 0.12065 -0.3048)
			(stroke
				(width 0.1)
				(type default)
			)
			(layer "F.Fab")
		)
		(fp_line
			(start 0.12065 -0.3048)
			(end 0.67945 -0.3048)
			(stroke
				(width 0.1)
				(type default)
			)
			(layer "F.Fab")
		)
		(fp_line
			(start 0.67945 -0.3048)
			(end 0.67945 0.3048)
			(stroke
				(width 0.1)
				(type default)
			)
			(layer "F.Fab")
		)
		(fp_line
			(start -0.67945 -0.305054)
			(end -0.12065 -0.305054)
			(stroke
				(width 0.1)
				(type default)
			)
			(layer "F.Fab")
		)
		(fp_line
			(start -0.12065 -0.305054)
			(end -0.12065 -0.2794)
			(stroke
				(width 0.1)
				(type default)
			)
			(layer "F.Fab")
		)
		(pad "1" smd circle
			(at -0.40005 0 270)
			(size 0 0)
			(layers "F.Cu" "F.Mask" "F.Paste")
			(net "PVDD18_S5_P1_REF")
		)
		(pad "2" smd circle
			(at 0.40005 0 270)
			(size 0 0)
			(layers "F.Cu" "F.Mask" "F.Paste")
			(net "GND")
		)
	)
)
